(kicad_pcb
	(version 20260206)
	(generator "pcbnew")
	(generator_version "10.0")
	(general
		(thickness 1.6)
		(legacy_teardrops no)
	)
	(paper "A4")
	(title_block
		(title "01162023_DA0F0TEBIF0_F0T_Expander_BD_F_brd_V02_OCP.brd")
		(comment 1 "Grand Teton / footprints 3726-3732 of 9728")
	)
	(layers
		(0 "F.Cu" signal "TOP")
		(4 "In1.Cu" signal "GND")
		(6 "In2.Cu" signal "VCC")
		(8 "In3.Cu" signal "VCC1")
		(10 "In4.Cu" signal "GND1")
		(12 "In5.Cu" signal "IN1")
		(14 "In6.Cu" signal "GND2")
		(16 "In7.Cu" signal "IN2")
		(18 "In8.Cu" signal "GND3")
		(20 "In9.Cu" signal "IN3")
		(22 "In10.Cu" signal "GND4")
		(24 "In11.Cu" signal "IN4")
		(26 "In12.Cu" signal "GND5")
		(28 "In13.Cu" signal "IN5")
		(30 "In14.Cu" signal "GND6")
		(32 "In15.Cu" signal "IN6")
		(34 "In16.Cu" signal "GND7")
		(2 "B.Cu" signal "BOTTOM")
		(9 "F.Adhes" user "F.Adhesive")
		(11 "B.Adhes" user "B.Adhesive")
		(13 "F.Paste" user "Package Geometry/Pastemask Top")
		(15 "B.Paste" user "Package Geometry/Pastemask Bottom")
		(5 "F.SilkS" user "Ref Des/Silkscreen Top")
		(7 "B.SilkS" user "Ref Des/Silkscreen Bottom")
		(1 "F.Mask" user "Board Geometry/Soldermask Top")
		(3 "B.Mask" user "Board Geometry/Soldermask Bottom")
		(17 "Dwgs.User" user "User.Drawings")
		(19 "Cmts.User" user "User.Comments")
		(21 "Eco1.User" user "User.Eco1")
		(23 "Eco2.User" user "User.Eco2")
		(25 "Edge.Cuts" user "Board Geometry/Outline")
		(27 "Margin" user)
		(31 "F.CrtYd" user "Package Geometry/Place Bound Top")
		(29 "B.CrtYd" user "Package Geometry/Place Bound Bottom")
		(35 "F.Fab" user "Ref Des/Assembly Top")
		(33 "B.Fab" user "Ref Des/Assembly Bottom")
	)
	(footprint ""
		(layer "F.Cu")
		(at 232.06964 -82.118708 180)
		(property "Reference" "R6725"
			(at 0 0 180)
			(layer "F.SilkS")
			(hide yes)
			(effects
				(font
					(size 1.27 1.27)
				)
			)
		)
		(property "Value" ""
			(at 0 0 180)
			(layer "F.Fab")
			(effects
				(font
					(size 1.27 1.27)
				)
			)
		)
		(duplicate_pad_numbers_are_jumpers no)
		(fp_line
			(start 0.7874 0.4064)
			(end -0.7874 0.4064)
			(stroke
				(width 0.1524)
				(type default)
			)
			(layer "F.SilkS")
		)
		(fp_line
			(start 0.7874 -0.4064)
			(end 0.7874 0.4064)
			(stroke
				(width 0.1524)
				(type default)
			)
			(layer "F.SilkS")
		)
		(fp_line
			(start -0.009652 -0.4064)
			(end 0.7874 -0.4064)
			(stroke
				(width 0.1524)
				(type default)
			)
			(layer "F.SilkS")
		)
		(fp_line
			(start -0.7874 0.4064)
			(end -0.7874 -0.4064)
			(stroke
				(width 0.1524)
				(type default)
			)
			(layer "F.SilkS")
		)
		(fp_line
			(start 0.67945 0.3048)
			(end 0.120396 0.3048)
			(stroke
				(width 0.1)
				(type default)
			)
			(layer "F.Fab")
		)
		(fp_line
			(start 0.67945 -0.3048)
			(end 0.67945 0.3048)
			(stroke
				(width 0.1)
				(type default)
			)
			(layer "F.Fab")
		)
		(fp_line
			(start 0.12065 -0.2794)
			(end 0.12065 -0.3048)
			(stroke
				(width 0.1)
				(type default)
			)
			(layer "F.Fab")
		)
		(fp_line
			(start 0.12065 -0.3048)
			(end 0.67945 -0.3048)
			(stroke
				(width 0.1)
				(type default)
			)
			(layer "F.Fab")
		)
		(fp_line
			(start 0.120396 0.3048)
			(end 0.120396 0.2794)
			(stroke
				(width 0.1)
				(type default)
			)
			(layer "F.Fab")
		)
		(fp_line
			(start 0.120396 0.2794)
			(end -0.12065 0.2794)
			(stroke
				(width 0.1)
				(type default)
			)
			(layer "F.Fab")
		)
		(fp_line
			(start -0.12065 0.3048)
			(end -0.67945 0.3048)
			(stroke
				(width 0.1)
				(type default)
			)
			(layer "F.Fab")
		)
		(fp_line
			(start -0.12065 0.2794)
			(end -0.12065 0.3048)
			(stroke
				(width 0.1)
				(type default)
			)
			(layer "F.Fab")
		)
		(fp_line
			(start -0.12065 -0.2794)
			(end 0.12065 -0.2794)
			(stroke
				(width 0.1)
				(type default)
			)
			(layer "F.Fab")
		)
		(fp_line
			(start -0.12065 -0.305054)
			(end -0.12065 -0.2794)
			(stroke
				(width 0.1)
				(type default)
			)
			(layer "F.Fab")
		)
		(fp_line
			(start -0.67945 0.3048)
			(end -0.67945 -0.305054)
			(stroke
				(width 0.1)
				(type default)
			)
			(layer "F.Fab")
		)
		(fp_line
			(start -0.67945 -0.305054)
			(end -0.12065 -0.305054)
			(stroke
				(width 0.1)
				(type default)
			)
			(layer "F.Fab")
		)
		(pad "1" smd rect
			(at -0.40005 0)
			(size 0.4572 0.508)
			(layers "F.Cu" "F.Mask" "F.Paste")
			(net "USB2_CP2108_SDB_DN")
		)
		(pad "2" smd rect
			(at 0.40005 0)
			(size 0.4572 0.508)
			(layers "F.Cu" "F.Mask" "F.Paste")
			(net "GND")
		)
	)
	(footprint ""
		(layer "F.Cu")
		(at 232.283 -231.394 90)
		(property "Reference" "R4524"
			(at 0 0 90)
			(layer "F.SilkS")
			(hide yes)
			(effects
				(font
					(size 1.27 1.27)
				)
			)
		)
		(property "Value" ""
			(at 0 0 90)
			(layer "F.Fab")
			(effects
				(font
					(size 1.27 1.27)
				)
			)
		)
		(duplicate_pad_numbers_are_jumpers no)
		(fp_line
			(start 0.7874 -0.4064)
			(end 0.7874 0.4064)
			(stroke
				(width 0.1524)
				(type default)
			)
			(layer "F.SilkS")
		)
		(fp_line
			(start -0.7874 -0.4064)
			(end 0.7874 -0.4064)
			(stroke
				(width 0.1524)
				(type default)
			)
			(layer "F.SilkS")
		)
		(fp_line
			(start 0.7874 0.4064)
			(end -0.7874 0.4064)
			(stroke
				(width 0.1524)
				(type default)
			)
			(layer "F.SilkS")
		)
		(fp_line
			(start -0.7874 0.4064)
			(end -0.7874 -0.4064)
			(stroke
				(width 0.1524)
				(type default)
			)
			(layer "F.SilkS")
		)
		(fp_line
			(start -0.12065 -0.305054)
			(end -0.12065 -0.2794)
			(stroke
				(width 0.1)
				(type default)
			)
			(layer "F.Fab")
		)
		(fp_line
			(start -0.67945 -0.305054)
			(end -0.12065 -0.305054)
			(stroke
				(width 0.1)
				(type default)
			)
			(layer "F.Fab")
		)
		(fp_line
			(start 0.67945 -0.3048)
			(end 0.67945 0.3048)
			(stroke
				(width 0.1)
				(type default)
			)
			(layer "F.Fab")
		)
		(fp_line
			(start 0.12065 -0.3048)
			(end 0.67945 -0.3048)
			(stroke
				(width 0.1)
				(type default)
			)
			(layer "F.Fab")
		)
		(fp_line
			(start 0.12065 -0.2794)
			(end 0.12065 -0.3048)
			(stroke
				(width 0.1)
				(type default)
			)
			(layer "F.Fab")
		)
		(fp_line
			(start -0.12065 -0.2794)
			(end 0.12065 -0.2794)
			(stroke
				(width 0.1)
				(type default)
			)
			(layer "F.Fab")
		)
		(fp_line
			(start 0.120396 0.2794)
			(end -0.12065 0.2794)
			(stroke
				(width 0.1)
				(type default)
			)
			(layer "F.Fab")
		)
		(fp_line
			(start -0.12065 0.2794)
			(end -0.12065 0.3048)
			(stroke
				(width 0.1)
				(type default)
			)
			(layer "F.Fab")
		)
		(fp_line
			(start 0.67945 0.3048)
			(end 0.120396 0.3048)
			(stroke
				(width 0.1)
				(type default)
			)
			(layer "F.Fab")
		)
		(fp_line
			(start 0.120396 0.3048)
			(end 0.120396 0.2794)
			(stroke
				(width 0.1)
				(type default)
			)
			(layer "F.Fab")
		)
		(fp_line
			(start -0.12065 0.3048)
			(end -0.67945 0.3048)
			(stroke
				(width 0.1)
				(type default)
			)
			(layer "F.Fab")
		)
		(fp_line
			(start -0.67945 0.3048)
			(end -0.67945 -0.305054)
			(stroke
				(width 0.1)
				(type default)
			)
			(layer "F.Fab")
		)
		(pad "1" smd circle
			(at -0.40005 0 90)
			(size 0 0)
			(layers "F.Cu" "F.Mask" "F.Paste")
			(net "SSD10_PWRDIS_BIC")
		)
		(pad "2" smd circle
			(at 0.40005 0 90)
			(size 0 0)
			(layers "F.Cu" "F.Mask" "F.Paste")
			(net "SSD10_PWRDIS_BIC_R")
		)
	)
	(footprint ""
		(layer "F.Cu")
		(at 335.264252 -29.079952 180)
		(property "Reference" "R6209"
			(at 0 0 180)
			(layer "F.SilkS")
			(hide yes)
			(effects
				(font
					(size 1.27 1.27)
				)
			)
		)
		(property "Value" ""
			(at 0 0 180)
			(layer "F.Fab")
			(effects
				(font
					(size 1.27 1.27)
				)
			)
		)
		(duplicate_pad_numbers_are_jumpers no)
		(fp_line
			(start 0.7874 0.4064)
			(end -0.7874 0.4064)
			(stroke
				(width 0.1524)
				(type default)
			)
			(layer "F.SilkS")
		)
		(fp_line
			(start 0.7874 -0.4064)
			(end 0.7874 0.4064)
			(stroke
				(width 0.1524)
				(type default)
			)
			(layer "F.SilkS")
		)
		(fp_line
			(start -0.7874 0.4064)
			(end -0.7874 -0.4064)
			(stroke
				(width 0.1524)
				(type default)
			)
			(layer "F.SilkS")
		)
		(fp_line
			(start -0.7874 -0.4064)
			(end 0.7874 -0.4064)
			(stroke
				(width 0.1524)
				(type default)
			)
			(layer "F.SilkS")
		)
		(fp_line
			(start 0.67945 0.3048)
			(end 0.120396 0.3048)
			(stroke
				(width 0.1)
				(type default)
			)
			(layer "F.Fab")
		)
		(fp_line
			(start 0.67945 -0.3048)
			(end 0.67945 0.3048)
			(stroke
				(width 0.1)
				(type default)
			)
			(layer "F.Fab")
		)
		(fp_line
			(start 0.12065 -0.2794)
			(end 0.12065 -0.3048)
			(stroke
				(width 0.1)
				(type default)
			)
			(layer "F.Fab")
		)
		(fp_line
			(start 0.12065 -0.3048)
			(end 0.67945 -0.3048)
			(stroke
				(width 0.1)
				(type default)
			)
			(layer "F.Fab")
		)
		(fp_line
			(start 0.120396 0.3048)
			(end 0.120396 0.2794)
			(stroke
				(width 0.1)
				(type default)
			)
			(layer "F.Fab")
		)
		(fp_line
			(start 0.120396 0.2794)
			(end -0.12065 0.2794)
			(stroke
				(width 0.1)
				(type default)
			)
			(layer "F.Fab")
		)
		(fp_line
			(start -0.12065 0.3048)
			(end -0.67945 0.3048)
			(stroke
				(width 0.1)
				(type default)
			)
			(layer "F.Fab")
		)
		(fp_line
			(start -0.12065 0.2794)
			(end -0.12065 0.3048)
			(stroke
				(width 0.1)
				(type default)
			)
			(layer "F.Fab")
		)
		(fp_line
			(start -0.12065 -0.2794)
			(end 0.12065 -0.2794)
			(stroke
				(width 0.1)
				(type default)
			)
			(layer "F.Fab")
		)
		(fp_line
			(start -0.12065 -0.305054)
			(end -0.12065 -0.2794)
			(stroke
				(width 0.1)
				(type default)
			)
			(layer "F.Fab")
		)
		(fp_line
			(start -0.67945 0.3048)
			(end -0.67945 -0.305054)
			(stroke
				(width 0.1)
				(type default)
			)
			(layer "F.Fab")
		)
		(fp_line
			(start -0.67945 -0.305054)
			(end -0.12065 -0.305054)
			(stroke
				(width 0.1)
				(type default)
			)
			(layer "F.Fab")
		)
		(pad "1" smd circle
			(at -0.40005 0 180)
			(size 0 0)
			(layers "F.Cu" "F.Mask" "F.Paste")
			(net "GND")
		)
		(pad "2" smd circle
			(at 0.40005 0 180)
			(size 0 0)
			(layers "F.Cu" "F.Mask" "F.Paste")
			(net "SSD11_PWRDIS_R")
		)
	)
	(footprint ""
		(layer "F.Cu")
		(at 358.41051 -123.947428 180)
		(property "Reference" "PR250"
			(at 0 0 180)
			(layer "F.SilkS")
			(hide yes)
			(effects
				(font
					(size 1.27 1.27)
				)
			)
		)
		(property "Value" ""
			(at 0 0 180)
			(layer "F.Fab")
			(effects
				(font
					(size 1.27 1.27)
				)
			)
		)
		(duplicate_pad_numbers_are_jumpers no)
		(fp_line
			(start 0.7874 0.4064)
			(end -0.7874 0.4064)
			(stroke
				(width 0.1524)
				(type default)
			)
			(layer "F.SilkS")
		)
		(fp_line
			(start 0.7874 -0.4064)
			(end 0.7874 0.4064)
			(stroke
				(width 0.1524)
				(type default)
			)
			(layer "F.SilkS")
		)
		(fp_line
			(start -0.7874 0.4064)
			(end -0.7874 -0.4064)
			(stroke
				(width 0.1524)
				(type default)
			)
			(layer "F.SilkS")
		)
		(fp_line
			(start -0.7874 -0.4064)
			(end 0.7874 -0.4064)
			(stroke
				(width 0.1524)
				(type default)
			)
			(layer "F.SilkS")
		)
		(fp_line
			(start 0.67945 0.3048)
			(end 0.120396 0.3048)
			(stroke
				(width 0.1)
				(type default)
			)
			(layer "F.Fab")
		)
		(fp_line
			(start 0.67945 -0.3048)
			(end 0.67945 0.3048)
			(stroke
				(width 0.1)
				(type default)
			)
			(layer "F.Fab")
		)
		(fp_line
			(start 0.12065 -0.2794)
			(end 0.12065 -0.3048)
			(stroke
				(width 0.1)
				(type default)
			)
			(layer "F.Fab")
		)
		(fp_line
			(start 0.12065 -0.3048)
			(end 0.67945 -0.3048)
			(stroke
				(width 0.1)
				(type default)
			)
			(layer "F.Fab")
		)
		(fp_line
			(start 0.120396 0.3048)
			(end 0.120396 0.2794)
			(stroke
				(width 0.1)
				(type default)
			)
			(layer "F.Fab")
		)
		(fp_line
			(start 0.120396 0.2794)
			(end -0.12065 0.2794)
			(stroke
				(width 0.1)
				(type default)
			)
			(layer "F.Fab")
		)
		(fp_line
			(start -0.12065 0.3048)
			(end -0.67945 0.3048)
			(stroke
				(width 0.1)
				(type default)
			)
			(layer "F.Fab")
		)
		(fp_line
			(start -0.12065 0.2794)
			(end -0.12065 0.3048)
			(stroke
				(width 0.1)
				(type default)
			)
			(layer "F.Fab")
		)
		(fp_line
			(start -0.12065 -0.2794)
			(end 0.12065 -0.2794)
			(stroke
				(width 0.1)
				(type default)
			)
			(layer "F.Fab")
		)
		(fp_line
			(start -0.12065 -0.305054)
			(end -0.12065 -0.2794)
			(stroke
				(width 0.1)
				(type default)
			)
			(layer "F.Fab")
		)
		(fp_line
			(start -0.67945 0.3048)
			(end -0.67945 -0.305054)
			(stroke
				(width 0.1)
				(type default)
			)
			(layer "F.Fab")
		)
		(fp_line
			(start -0.67945 -0.305054)
			(end -0.12065 -0.305054)
			(stroke
				(width 0.1)
				(type default)
			)
			(layer "F.Fab")
		)
		(pad "1" smd circle
			(at -0.40005 0 180)
			(size 0 0)
			(layers "F.Cu" "F.Mask" "F.Paste")
			(net "P3V3_NIC6_OCP")
		)
		(pad "2" smd circle
			(at 0.40005 0 180)
			(size 0 0)
			(layers "F.Cu" "F.Mask" "F.Paste")
			(net "GND")
		)
	)
	(footprint ""
		(layer "F.Cu")
		(at 143.317468 -387.77799 -90)
		(property "Reference" "C4080"
			(at 0 0 270)
			(layer "F.SilkS")
			(hide yes)
			(effects
				(font
					(size 1.27 1.27)
				)
			)
		)
		(property "Value" ""
			(at 0 0 270)
			(layer "F.Fab")
			(effects
				(font
					(size 1.27 1.27)
				)
			)
		)
		(duplicate_pad_numbers_are_jumpers no)
		(fp_line
			(start -0.7874 0.4064)
			(end -0.7874 -0.4064)
			(stroke
				(width 0.1524)
				(type default)
			)
			(layer "F.SilkS")
		)
		(fp_line
			(start 0.7874 0.4064)
			(end -0.7874 0.4064)
			(stroke
				(width 0.1524)
				(type default)
			)
			(layer "F.SilkS")
		)
		(fp_line
			(start -0.7874 -0.4064)
			(end 0.7874 -0.4064)
			(stroke
				(width 0.1524)
				(type default)
			)
			(layer "F.SilkS")
		)
		(fp_line
			(start 0.7874 -0.4064)
			(end 0.7874 0.4064)
			(stroke
				(width 0.1524)
				(type default)
			)
			(layer "F.SilkS")
		)
		(fp_line
			(start -0.67945 0.3048)
			(end -0.67945 -0.305054)
			(stroke
				(width 0.1)
				(type default)
			)
			(layer "F.Fab")
		)
		(fp_line
			(start -0.12065 0.3048)
			(end -0.67945 0.3048)
			(stroke
				(width 0.1)
				(type default)
			)
			(layer "F.Fab")
		)
		(fp_line
			(start 0.120396 0.3048)
			(end 0.120396 0.2794)
			(stroke
				(width 0.1)
				(type default)
			)
			(layer "F.Fab")
		)
		(fp_line
			(start 0.67945 0.3048)
			(end 0.120396 0.3048)
			(stroke
				(width 0.1)
				(type default)
			)
			(layer "F.Fab")
		)
		(fp_line
			(start -0.12065 0.2794)
			(end -0.12065 0.3048)
			(stroke
				(width 0.1)
				(type default)
			)
			(layer "F.Fab")
		)
		(fp_line
			(start 0.120396 0.2794)
			(end -0.12065 0.2794)
			(stroke
				(width 0.1)
				(type default)
			)
			(layer "F.Fab")
		)
		(fp_line
			(start -0.12065 -0.2794)
			(end 0.12065 -0.2794)
			(stroke
				(width 0.1)
				(type default)
			)
			(layer "F.Fab")
		)
		(fp_line
			(start 0.12065 -0.2794)
			(end 0.12065 -0.3048)
			(stroke
				(width 0.1)
				(type default)
			)
			(layer "F.Fab")
		)
		(fp_line
			(start 0.12065 -0.3048)
			(end 0.67945 -0.3048)
			(stroke
				(width 0.1)
				(type default)
			)
			(layer "F.Fab")
		)
		(fp_line
			(start 0.67945 -0.3048)
			(end 0.67945 0.3048)
			(stroke
				(width 0.1)
				(type default)
			)
			(layer "F.Fab")
		)
		(fp_line
			(start -0.67945 -0.305054)
			(end -0.12065 -0.305054)
			(stroke
				(width 0.1)
				(type default)
			)
			(layer "F.Fab")
		)
		(fp_line
			(start -0.12065 -0.305054)
			(end -0.12065 -0.2794)
			(stroke
				(width 0.1)
				(type default)
			)
			(layer "F.Fab")
		)
		(pad "1" smd circle
			(at -0.40005 0 270)
			(size 0 0)
			(layers "F.Cu" "F.Mask" "F.Paste")
			(net "GND")
		)
		(pad "2" smd circle
			(at 0.40005 0 270)
			(size 0 0)
			(layers "F.Cu" "F.Mask" "F.Paste")
			(net "MB_BMC_MON")
		)
	)
	(footprint ""
		(layer "F.Cu")
		(at 126.79299 -151.737822 180)
		(property "Reference" "PR6885"
			(at 0 0 180)
			(layer "F.SilkS")
			(hide yes)
			(effects
				(font
					(size 1.27 1.27)
				)
			)
		)
		(property "Value" ""
			(at 0 0 180)
			(layer "F.Fab")
			(effects
				(font
					(size 1.27 1.27)
				)
			)
		)
		(duplicate_pad_numbers_are_jumpers no)
		(fp_line
			(start 0.7874 0.4064)
			(end -0.7874 0.4064)
			(stroke
				(width 0.1524)
				(type default)
			)
			(layer "F.SilkS")
		)
		(fp_line
			(start 0.7874 -0.4064)
			(end 0.7874 0.4064)
			(stroke
				(width 0.1524)
				(type default)
			)
			(layer "F.SilkS")
		)
		(fp_line
			(start -0.7874 0.4064)
			(end -0.7874 -0.4064)
			(stroke
				(width 0.1524)
				(type default)
			)
			(layer "F.SilkS")
		)
		(fp_line
			(start -0.7874 -0.4064)
			(end 0.7874 -0.4064)
			(stroke
				(width 0.1524)
				(type default)
			)
			(layer "F.SilkS")
		)
		(fp_line
			(start 0.67945 0.3048)
			(end 0.120396 0.3048)
			(stroke
				(width 0.1)
				(type default)
			)
			(layer "F.Fab")
		)
		(fp_line
			(start 0.67945 -0.3048)
			(end 0.67945 0.3048)
			(stroke
				(width 0.1)
				(type default)
			)
			(layer "F.Fab")
		)
		(fp_line
			(start 0.12065 -0.2794)
			(end 0.12065 -0.3048)
			(stroke
				(width 0.1)
				(type default)
			)
			(layer "F.Fab")
		)
		(fp_line
			(start 0.12065 -0.3048)
			(end 0.67945 -0.3048)
			(stroke
				(width 0.1)
				(type default)
			)
			(layer "F.Fab")
		)
		(fp_line
			(start 0.120396 0.3048)
			(end 0.120396 0.2794)
			(stroke
				(width 0.1)
				(type default)
			)
			(layer "F.Fab")
		)
		(fp_line
			(start 0.120396 0.2794)
			(end -0.12065 0.2794)
			(stroke
				(width 0.1)
				(type default)
			)
			(layer "F.Fab")
		)
		(fp_line
			(start -0.12065 0.3048)
			(end -0.67945 0.3048)
			(stroke
				(width 0.1)
				(type default)
			)
			(layer "F.Fab")
		)
		(fp_line
			(start -0.12065 0.2794)
			(end -0.12065 0.3048)
			(stroke
				(width 0.1)
				(type default)
			)
			(layer "F.Fab")
		)
		(fp_line
			(start -0.12065 -0.2794)
			(end 0.12065 -0.2794)
			(stroke
				(width 0.1)
				(type default)
			)
			(layer "F.Fab")
		)
		(fp_line
			(start -0.12065 -0.305054)
			(end -0.12065 -0.2794)
			(stroke
				(width 0.1)
				(type default)
			)
			(layer "F.Fab")
		)
		(fp_line
			(start -0.67945 0.3048)
			(end -0.67945 -0.305054)
			(stroke
				(width 0.1)
				(type default)
			)
			(layer "F.Fab")
		)
		(fp_line
			(start -0.67945 -0.305054)
			(end -0.12065 -0.305054)
			(stroke
				(width 0.1)
				(type default)
			)
			(layer "F.Fab")
		)
		(pad "1" smd circle
			(at -0.40005 0 180)
			(size 0 0)
			(layers "F.Cu" "F.Mask" "F.Paste")
			(net "P12V_NIC2_R")
		)
		(pad "2" smd circle
			(at 0.40005 0 180)
			(size 0 0)
			(layers "F.Cu" "F.Mask" "F.Paste")
			(net "P12V_NIC2_CO_AVIN_PD")
		)
	)
	(footprint ""
		(layer "F.Cu")
		(at 299.875702 -350.098614 90)
		(property "Reference" "C584"
			(at 0 0 90)
			(layer "F.SilkS")
			(hide yes)
			(effects
				(font
					(size 1.27 1.27)
				)
			)
		)
		(property "Value" ""
			(at 0 0 90)
			(layer "F.Fab")
			(effects
				(font
					(size 1.27 1.27)
				)
			)
		)
		(duplicate_pad_numbers_are_jumpers no)
		(fp_line
			(start 0.299974 -0.150114)
			(end 0.299974 0.150114)
			(stroke
				(width 0.1)
				(type default)
			)
			(layer "F.Fab")
		)
		(fp_line
			(start -0.299974 -0.150114)
			(end 0.299974 -0.150114)
			(stroke
				(width 0.1)
				(type default)
			)
			(layer "F.Fab")
		)
		(fp_line
			(start 0.299974 0.150114)
			(end -0.299974 0.150114)
			(stroke
				(width 0.1)
				(type default)
			)
			(layer "F.Fab")
		)
		(fp_line
			(start -0.299974 0.150114)
			(end -0.299974 -0.150114)
			(stroke
				(width 0.1)
				(type default)
			)
			(layer "F.Fab")
		)
		(pad "1" smd rect
			(at -0.2667 0 90)
			(size 0.3048 0.381)
			(layers "F.Cu" "F.Mask" "F.Paste")
			(net "P5E_PEX2_STN7_TX_DN<127>")
		)
		(pad "2" smd rect
			(at 0.2667 0 90)
			(size 0.3048 0.381)
			(layers "F.Cu" "F.Mask" "F.Paste")
			(net "P5E_PEX2_STN7_TX_C_DN<127>")
		)
	)
)
